# S9S_MB_2U (Grand Teton) — schematic netlist excerpt (pin names and nets, part order shuffled) for the footprints in the layout excerpt that follows; sources: Cadence DE-HDL packaged netlist, KiCad conversion of 03242023_DA0F0TMBIJ0_F0T_Motherboard_J_brd_V01_OCP.brd

J43  CONN8_210HP1080BR1  CONN8_210-HP1-080BR1 IO  pkg HEADER1X8XE  page 221
  \1\  = P3V3_AUX_BMC_D
  \2\  = JTAG_BMC_PLD_TDO
  \3\  = JTAG_BMC_PLD_TDI
  \4\  = TP_PLD_CONN_P4
  \5\  = TP_PLD_CONN_P5
  \6\  = JTAG_BMC_PLD_TMS
  \7\  = GND
  \8\  = JTAG_BMC_PLD_TCK

PC2235  Q_CAP  100NF 50V 10% X7R  pkg C0402  page 242 : A = P12V_SCM_IMON ; B = GND

(kicad_pcb
	(version 20260206)
	(generator "pcbnew")
	(generator_version "10.0")
	(general
		(thickness 1.6)
		(legacy_teardrops no)
	)
	(paper "A4")
	(title_block
		(title "03242023_DA0F0TMBIJ0_F0T_Motherboard_J_brd_V01_OCP.brd")
		(comment 1 "Grand Teton / footprints 2239-2240 of 6105")
	)
	(layers
		(0 "F.Cu" signal "TOP")
		(4 "In1.Cu" signal "GND")
		(6 "In2.Cu" signal "IN1")
		(8 "In3.Cu" signal "GND1")
		(10 "In4.Cu" signal "IN2")
		(12 "In5.Cu" signal "GND2")
		(14 "In6.Cu" signal "IN3")
		(16 "In7.Cu" signal "GND3")
		(18 "In8.Cu" signal "VCC")
		(20 "In9.Cu" signal "VCC1")
		(22 "In10.Cu" signal "GND4")
		(24 "In11.Cu" signal "IN4")
		(26 "In12.Cu" signal "GND5")
		(28 "In13.Cu" signal "IN5")
		(30 "In14.Cu" signal "GND6")
		(32 "In15.Cu" signal "IN6")
		(34 "In16.Cu" signal "GND7")
		(2 "B.Cu" signal "BOTTOM")
		(9 "F.Adhes" user "F.Adhesive")
		(11 "B.Adhes" user "B.Adhesive")
		(13 "F.Paste" user "Package Geometry/Pastemask Top")
		(15 "B.Paste" user "Package Geometry/Pastemask Bottom")
		(5 "F.SilkS" user "Ref Des/Silkscreen Top")
		(7 "B.SilkS" user "Ref Des/Silkscreen Bottom")
		(1 "F.Mask" user "Board Geometry/Soldermask Top")
		(3 "B.Mask" user "Board Geometry/Soldermask Bottom")
		(17 "Dwgs.User" user "User.Drawings")
		(19 "Cmts.User" user "User.Comments")
		(21 "Eco1.User" user "User.Eco1")
		(23 "Eco2.User" user "User.Eco2")
		(25 "Edge.Cuts" user "Board Geometry/Outline")
		(27 "Margin" user)
		(31 "F.CrtYd" user "Package Geometry/Place Bound Top")
		(29 "B.CrtYd" user "Package Geometry/Place Bound Bottom")
		(35 "F.Fab" user "Ref Des/Assembly Top")
		(33 "B.Fab" user "Ref Des/Assembly Bottom")
	)
	(footprint ""
		(layer "F.Cu")
		(at 174.613062 -32.935672 90)
		(property "Reference" "PC2235"
			(at 0 0 90)
			(layer "F.SilkS")
			(hide yes)
			(effects
				(font
					(size 1.27 1.27)
				)
			)
		)
		(property "Value" ""
			(at 0 0 90)
			(layer "F.Fab")
			(effects
				(font
					(size 1.27 1.27)
				)
			)
		)
		(duplicate_pad_numbers_are_jumpers no)
		(fp_line
			(start 0.7874 -0.4064)
			(end 0.7874 0.4064)
			(stroke
				(width 0.1524)
				(type default)
			)
			(layer "F.SilkS")
		)
		(fp_line
			(start -0.7874 -0.4064)
			(end 0.7874 -0.4064)
			(stroke
				(width 0.1524)
				(type default)
			)
			(layer "F.SilkS")
		)
		(fp_line
			(start 0.7874 0.4064)
			(end -0.7874 0.4064)
			(stroke
				(width 0.1524)
				(type default)
			)
			(layer "F.SilkS")
		)
		(fp_line
			(start -0.7874 0.4064)
			(end -0.7874 -0.4064)
			(stroke
				(width 0.1524)
				(type default)
			)
			(layer "F.SilkS")
		)
		(fp_line
			(start -0.12065 -0.305054)
			(end -0.12065 -0.2794)
			(stroke
				(width 0.1)
				(type default)
			)
			(layer "F.Fab")
		)
		(fp_line
			(start -0.67945 -0.305054)
			(end -0.12065 -0.305054)
			(stroke
				(width 0.1)
				(type default)
			)
			(layer "F.Fab")
		)
		(fp_line
			(start 0.67945 -0.3048)
			(end 0.67945 0.3048)
			(stroke
				(width 0.1)
				(type default)
			)
			(layer "F.Fab")
		)
		(fp_line
			(start 0.12065 -0.3048)
			(end 0.67945 -0.3048)
			(stroke
				(width 0.1)
				(type default)
			)
			(layer "F.Fab")
		)
		(fp_line
			(start 0.12065 -0.2794)
			(end 0.12065 -0.3048)
			(stroke
				(width 0.1)
				(type default)
			)
			(layer "F.Fab")
		)
		(fp_line
			(start -0.12065 -0.2794)
			(end 0.12065 -0.2794)
			(stroke
				(width 0.1)
				(type default)
			)
			(layer "F.Fab")
		)
		(fp_line
			(start 0.120396 0.2794)
			(end -0.12065 0.2794)
			(stroke
				(width 0.1)
				(type default)
			)
			(layer "F.Fab")
		)
		(fp_line
			(start -0.12065 0.2794)
			(end -0.12065 0.3048)
			(stroke
				(width 0.1)
				(type default)
			)
			(layer "F.Fab")
		)
		(fp_line
			(start 0.67945 0.3048)
			(end 0.120396 0.3048)
			(stroke
				(width 0.1)
				(type default)
			)
			(layer "F.Fab")
		)
		(fp_line
			(start 0.120396 0.3048)
			(end 0.120396 0.2794)
			(stroke
				(width 0.1)
				(type default)
			)
			(layer "F.Fab")
		)
		(fp_line
			(start -0.12065 0.3048)
			(end -0.67945 0.3048)
			(stroke
				(width 0.1)
				(type default)
			)
			(layer "F.Fab")
		)
		(fp_line
			(start -0.67945 0.3048)
			(end -0.67945 -0.305054)
			(stroke
				(width 0.1)
				(type default)
			)
			(layer "F.Fab")
		)
		(pad "1" smd circle
			(at -0.40005 0 90)
			(size 0 0)
			(layers "F.Cu" "F.Mask" "F.Paste")
			(net "P12V_SCM_IMON")
		)
		(pad "2" smd circle
			(at 0.40005 0 90)
			(size 0 0)
			(layers "F.Cu" "F.Mask" "F.Paste")
			(net "GND")
		)
	)
	(footprint ""
		(layer "F.Cu")
		(at 132.08 -70.749922 -90)
		(property "Reference" "J43"
			(at -1.860296 7.31012 0)
			(unlocked yes)
			(layer "F.SilkS")
			(effects
				(font
					(size 0.7874 0.5842)
					(thickness 0.1524)
				)
				(justify left)
			)
		)
		(property "Value" ""
			(at 0 0 270)
			(layer "F.Fab")
			(effects
				(font
					(size 1.27 1.27)
				)
			)
		)
		(duplicate_pad_numbers_are_jumpers no)
		(fp_line
			(start -1.249934 19.100038)
			(end -1.249934 -1.320038)
			(stroke
				(width 0.1524)
				(type default)
			)
			(layer "F.SilkS")
		)
		(fp_line
			(start 1.249934 19.100038)
			(end -1.249934 19.100038)
			(stroke
				(width 0.1524)
				(type default)
			)
			(layer "F.SilkS")
		)
		(fp_line
			(start -1.249934 -1.320038)
			(end 1.249934 -1.320038)
			(stroke
				(width 0.1524)
				(type default)
			)
			(layer "F.SilkS")
		)
		(fp_line
			(start 1.249934 -1.320038)
			(end 1.249934 19.100038)
			(stroke
				(width 0.1524)
				(type default)
			)
			(layer "F.SilkS")
		)
		(fp_poly
			(pts
				(xy 2.807208 0.48641) (xy 1.529842 -0.1524) (xy 2.807208 -0.79121)
			)
			(stroke
				(width 0)
				(type default)
			)
			(fill yes)
			(layer "F.SilkS")
		)
		(fp_line
			(start -1.249934 19.100038)
			(end -1.249934 -1.320038)
			(stroke
				(width 0.1)
				(type default)
			)
			(layer "F.Fab")
		)
		(fp_line
			(start 1.249934 19.100038)
			(end -1.249934 19.100038)
			(stroke
				(width 0.1)
				(type default)
			)
			(layer "F.Fab")
		)
		(fp_line
			(start -1.249934 -1.320038)
			(end 1.249934 -1.320038)
			(stroke
				(width 0.1)
				(type default)
			)
			(layer "F.Fab")
		)
		(fp_line
			(start 1.249934 -1.320038)
			(end 1.249934 19.100038)
			(stroke
				(width 0.1)
				(type default)
			)
			(layer "F.Fab")
		)
		(fp_poly
			(pts
				(xy -2.7432 0.63881) (xy -2.7432 -0.63881) (xy -1.465834 0)
			)
			(stroke
				(width 0)
				(type default)
			)
			(fill yes)
			(layer "F.Fab")
		)
		(fp_text user "8"
			(at -1.7526 17.80667 270)
			(unlocked yes)
			(layer "F.SilkS")
			(effects
				(font
					(size 0.7874 0.5842)
					(thickness 0.1524)
				)
			)
		)
		(fp_text user "8"
			(at 1.881124 17.759934 0)
			(unlocked yes)
			(layer "B.SilkS")
			(effects
				(font
					(size 0.7874 0.5842)
					(thickness 0.1524)
				)
				(justify mirror)
			)
		)
		(fp_text user "1"
			(at 1.878584 -0.068326 0)
			(unlocked yes)
			(layer "B.SilkS")
			(effects
				(font
					(size 0.7874 0.5842)
					(thickness 0.1524)
				)
				(justify mirror)
			)
		)
		(fp_text user "8"
			(at -1.1938 17.80667 270)
			(unlocked yes)
			(layer "B.Fab")
			(effects
				(font
					(size 0.7874 0.5842)
					(thickness 0.1524)
				)
				(justify mirror)
			)
		)
		(fp_text user "1"
			(at -1.1176 -0.02413 270)
			(unlocked yes)
			(layer "B.Fab")
			(effects
				(font
					(size 0.7874 0.5842)
					(thickness 0.1524)
				)
				(justify mirror)
			)
		)
		(fp_text user "8"
			(at -1.7526 17.80667 270)
			(unlocked yes)
			(layer "F.Fab")
			(effects
				(font
					(size 0.7874 0.5842)
					(thickness 0.1524)
				)
			)
		)
		(pad "1" thru_hole rect
			(at 0 0 270)
			(size 1.5494 1.5494)
			(drill 1.0414)
			(layers "*.Cu" "*.Mask")
			(remove_unused_layers no)
			(net "P3V3_AUX_BMC_D")
			(clearance 0)
			(padstack
				(mode front_inner_back)
				(layer "Inner"
					(shape circle)
					(size 1.5494 1.5494)
					(clearance 0)
				)
				(layer "B.Cu"
					(shape rect)
					(size 1.5494 1.5494)
					(clearance 0)
				)
			)
		)
		(pad "2" thru_hole circle
			(at 0 2.54 270)
			(size 1.5494 1.5494)
			(drill 1.0414)
			(layers "*.Cu" "*.Mask")
			(remove_unused_layers no)
			(net "JTAG_BMC_PLD_TDO")
			(clearance 0)
		)
		(pad "3" thru_hole circle
			(at 0 5.08 270)
			(size 1.5494 1.5494)
			(drill 1.0414)
			(layers "*.Cu" "*.Mask")
			(remove_unused_layers no)
			(net "JTAG_BMC_PLD_TDI")
			(clearance 0)
		)
		(pad "4" thru_hole circle
			(at 0 7.62 270)
			(size 1.5494 1.5494)
			(drill 1.0414)
			(layers "*.Cu" "*.Mask")
			(remove_unused_layers no)
			(net "TP_PLD_CONN_P4")
			(clearance 0)
		)
		(pad "5" thru_hole circle
			(at 0 10.16 270)
			(size 1.5494 1.5494)
			(drill 1.0414)
			(layers "*.Cu" "*.Mask")
			(remove_unused_layers no)
			(net "TP_PLD_CONN_P5")
			(clearance 0)
		)
		(pad "6" thru_hole circle
			(at 0 12.7 270)
			(size 1.5494 1.5494)
			(drill 1.0414)
			(layers "*.Cu" "*.Mask")
			(remove_unused_layers no)
			(net "JTAG_BMC_PLD_TMS")
			(clearance 0)
		)
		(pad "7" thru_hole circle
			(at 0 15.24 270)
			(size 1.5494 1.5494)
			(drill 1.0414)
			(layers "*.Cu" "*.Mask")
			(remove_unused_layers no)
			(net "GND")
			(clearance 0)
		)
		(pad "8" thru_hole circle
			(at 0 17.78 270)
			(size 1.5494 1.5494)
			(drill 1.0414)
			(layers "*.Cu" "*.Mask")
			(remove_unused_layers no)
			(net "JTAG_BMC_PLD_TCK")
			(clearance 0)
		)
	)
)
